# T6G (Grand Teton) — schematic netlist excerpt (pin names and nets, part order shuffled) for the footprints in the layout excerpt that follows; sources: Cadence DE-HDL packaged netlist, KiCad conversion of 04192023_DAF0TMB3IC0_F0TG_MB_C_brd_V02_OCP.brd

D77  Q_LED  IC  pkg SMLF  page 255 : A = LED_PWRGD_PVDDIO_P0_R ; C = LED_PWRGD_PVDDIO_P0_D
PC263_2  Q_CAP  1UF 25V 10% X6S  pkg C0402  page 211 : A = SW_P12V_AUX_PVDDCR_CPU0_P1_FLT ; B = GND
C899  Q_CAP_DIFFBUS  DIFF BUS_0.22UF 6.3V 20% X6S  pkg C0201  page 64 : \1\ = P5E_CPU0_P3_TX_C_DP<1> ; \2\ = P5E_CPU0_P3_TX_DP<1>

(kicad_pcb
	(version 20260206)
	(generator "pcbnew")
	(generator_version "10.0")
	(general
		(thickness 1.6)
		(legacy_teardrops no)
	)
	(paper "A4")
	(title_block
		(title "04192023_DAF0TMB3IC0_F0TG_MB_C_brd_V02_OCP.brd")
		(comment 1 "Grand Teton / footprints 2324-2326 of 8354")
	)
	(layers
		(0 "F.Cu" signal "TOP")
		(4 "In1.Cu" signal "GND")
		(6 "In2.Cu" signal "IN1")
		(8 "In3.Cu" signal "GND1")
		(10 "In4.Cu" signal "IN2")
		(12 "In5.Cu" signal "GND2")
		(14 "In6.Cu" signal "IN3")
		(16 "In7.Cu" signal "GND3")
		(18 "In8.Cu" signal "VCC")
		(20 "In9.Cu" signal "VCC1")
		(22 "In10.Cu" signal "GND4")
		(24 "In11.Cu" signal "IN4")
		(26 "In12.Cu" signal "GND5")
		(28 "In13.Cu" signal "IN5")
		(30 "In14.Cu" signal "GND6")
		(32 "In15.Cu" signal "IN6")
		(34 "In16.Cu" signal "GND7")
		(2 "B.Cu" signal "BOTTOM")
		(9 "F.Adhes" user "F.Adhesive")
		(11 "B.Adhes" user "B.Adhesive")
		(13 "F.Paste" user "Package Geometry/Pastemask Top")
		(15 "B.Paste" user "Package Geometry/Pastemask Bottom")
		(5 "F.SilkS" user "Ref Des/Silkscreen Top")
		(7 "B.SilkS" user "Ref Des/Silkscreen Bottom")
		(1 "F.Mask" user "Board Geometry/Soldermask Top")
		(3 "B.Mask" user "Board Geometry/Soldermask Bottom")
		(17 "Dwgs.User" user "User.Drawings")
		(19 "Cmts.User" user "User.Comments")
		(21 "Eco1.User" user "User.Eco1")
		(23 "Eco2.User" user "User.Eco2")
		(25 "Edge.Cuts" user "Board Geometry/Outline")
		(27 "Margin" user)
		(31 "F.CrtYd" user "Package Geometry/Place Bound Top")
		(29 "B.CrtYd" user "Package Geometry/Place Bound Bottom")
		(35 "F.Fab" user "Ref Des/Assembly Top")
		(33 "B.Fab" user "Ref Des/Assembly Bottom")
	)
	(footprint ""
		(layer "F.Cu")
		(at 87.04834 -182.578248 90)
		(property "Reference" "PC263_2"
			(at 0 0 90)
			(layer "F.SilkS")
			(hide yes)
			(effects
				(font
					(size 1.27 1.27)
				)
			)
		)
		(property "Value" ""
			(at 0 0 90)
			(layer "F.Fab")
			(effects
				(font
					(size 1.27 1.27)
				)
			)
		)
		(duplicate_pad_numbers_are_jumpers no)
		(fp_line
			(start 0.7874 -0.4064)
			(end 0.7874 0.4064)
			(stroke
				(width 0.1524)
				(type default)
			)
			(layer "F.SilkS")
		)
		(fp_line
			(start -0.7874 -0.4064)
			(end 0.7874 -0.4064)
			(stroke
				(width 0.1524)
				(type default)
			)
			(layer "F.SilkS")
		)
		(fp_line
			(start 0.7874 0.4064)
			(end -0.7874 0.4064)
			(stroke
				(width 0.1524)
				(type default)
			)
			(layer "F.SilkS")
		)
		(fp_line
			(start -0.7874 0.4064)
			(end -0.7874 -0.4064)
			(stroke
				(width 0.1524)
				(type default)
			)
			(layer "F.SilkS")
		)
		(fp_line
			(start -0.12065 -0.305054)
			(end -0.12065 -0.2794)
			(stroke
				(width 0.1)
				(type default)
			)
			(layer "F.Fab")
		)
		(fp_line
			(start -0.67945 -0.305054)
			(end -0.12065 -0.305054)
			(stroke
				(width 0.1)
				(type default)
			)
			(layer "F.Fab")
		)
		(fp_line
			(start 0.67945 -0.3048)
			(end 0.67945 0.3048)
			(stroke
				(width 0.1)
				(type default)
			)
			(layer "F.Fab")
		)
		(fp_line
			(start 0.12065 -0.3048)
			(end 0.67945 -0.3048)
			(stroke
				(width 0.1)
				(type default)
			)
			(layer "F.Fab")
		)
		(fp_line
			(start 0.12065 -0.2794)
			(end 0.12065 -0.3048)
			(stroke
				(width 0.1)
				(type default)
			)
			(layer "F.Fab")
		)
		(fp_line
			(start -0.12065 -0.2794)
			(end 0.12065 -0.2794)
			(stroke
				(width 0.1)
				(type default)
			)
			(layer "F.Fab")
		)
		(fp_line
			(start 0.120396 0.2794)
			(end -0.12065 0.2794)
			(stroke
				(width 0.1)
				(type default)
			)
			(layer "F.Fab")
		)
		(fp_line
			(start -0.12065 0.2794)
			(end -0.12065 0.3048)
			(stroke
				(width 0.1)
				(type default)
			)
			(layer "F.Fab")
		)
		(fp_line
			(start 0.67945 0.3048)
			(end 0.120396 0.3048)
			(stroke
				(width 0.1)
				(type default)
			)
			(layer "F.Fab")
		)
		(fp_line
			(start 0.120396 0.3048)
			(end 0.120396 0.2794)
			(stroke
				(width 0.1)
				(type default)
			)
			(layer "F.Fab")
		)
		(fp_line
			(start -0.12065 0.3048)
			(end -0.67945 0.3048)
			(stroke
				(width 0.1)
				(type default)
			)
			(layer "F.Fab")
		)
		(fp_line
			(start -0.67945 0.3048)
			(end -0.67945 -0.305054)
			(stroke
				(width 0.1)
				(type default)
			)
			(layer "F.Fab")
		)
		(pad "1" smd circle
			(at -0.40005 0 90)
			(size 0 0)
			(layers "F.Cu" "F.Mask" "F.Paste")
			(net "SW_P12V_AUX_PVDDCR_CPU0_P1_FLT")
		)
		(pad "2" smd circle
			(at 0.40005 0 90)
			(size 0 0)
			(layers "F.Cu" "F.Mask" "F.Paste")
			(net "GND")
		)
	)
	(footprint ""
		(layer "F.Cu")
		(at 366.06734 -384.32486 180)
		(property "Reference" "C899"
			(at 0 0 180)
			(layer "F.SilkS")
			(hide yes)
			(effects
				(font
					(size 1.27 1.27)
				)
			)
		)
		(property "Value" ""
			(at 0 0 180)
			(layer "F.Fab")
			(effects
				(font
					(size 1.27 1.27)
				)
			)
		)
		(duplicate_pad_numbers_are_jumpers no)
		(fp_line
			(start 0.299974 0.150114)
			(end -0.299974 0.150114)
			(stroke
				(width 0.1)
				(type default)
			)
			(layer "F.Fab")
		)
		(fp_line
			(start 0.299974 -0.150114)
			(end 0.299974 0.150114)
			(stroke
				(width 0.1)
				(type default)
			)
			(layer "F.Fab")
		)
		(fp_line
			(start -0.299974 0.150114)
			(end -0.299974 -0.150114)
			(stroke
				(width 0.1)
				(type default)
			)
			(layer "F.Fab")
		)
		(fp_line
			(start -0.299974 -0.150114)
			(end 0.299974 -0.150114)
			(stroke
				(width 0.1)
				(type default)
			)
			(layer "F.Fab")
		)
		(pad "1" smd rect
			(at -0.2667 0 180)
			(size 0.3048 0.381)
			(layers "F.Cu" "F.Mask" "F.Paste")
			(net "P5E_CPU0_P3_TX_C_DP<1>")
		)
		(pad "2" smd rect
			(at 0.2667 0 180)
			(size 0.3048 0.381)
			(layers "F.Cu" "F.Mask" "F.Paste")
			(net "P5E_CPU0_P3_TX_DP<1>")
		)
	)
	(footprint ""
		(layer "F.Cu")
		(at 330.731876 -70.098412 90)
		(property "Reference" "D77"
			(at -3.934714 -0.691642 90)
			(unlocked yes)
			(layer "F.SilkS")
			(effects
				(font
					(size 0.7874 0.5842)
					(thickness 0.1524)
				)
				(justify left)
			)
		)
		(property "Value" ""
			(at 0 0 90)
			(layer "F.Fab")
			(effects
				(font
					(size 1.27 1.27)
				)
			)
		)
		(duplicate_pad_numbers_are_jumpers no)
		(fp_line
			(start 1.16078 -0.4826)
			(end 1.16078 0.4826)
			(stroke
				(width 0.1524)
				(type default)
			)
			(layer "F.SilkS")
		)
		(fp_line
			(start 1.03378 -0.4826)
			(end 1.03378 0.4826)
			(stroke
				(width 0.1524)
				(type default)
			)
			(layer "F.SilkS")
		)
		(fp_line
			(start 0.90678 -0.4826)
			(end 0.90678 0.4826)
			(stroke
				(width 0.1524)
				(type default)
			)
			(layer "F.SilkS")
		)
		(fp_line
			(start -0.64008 -0.4826)
			(end 1.16078 -0.4826)
			(stroke
				(width 0.1524)
				(type default)
			)
			(layer "F.SilkS")
		)
		(fp_line
			(start -0.79248 -0.4826)
			(end 1.03378 -0.4826)
			(stroke
				(width 0.1524)
				(type default)
			)
			(layer "F.SilkS")
		)
		(fp_line
			(start -0.89408 -0.4826)
			(end 0.90678 -0.4826)
			(stroke
				(width 0.1524)
				(type default)
			)
			(layer "F.SilkS")
		)
		(fp_line
			(start 1.16078 0.4826)
			(end -0.64008 0.4826)
			(stroke
				(width 0.1524)
				(type default)
			)
			(layer "F.SilkS")
		)
		(fp_line
			(start 1.03378 0.4826)
			(end -0.79248 0.4826)
			(stroke
				(width 0.1524)
				(type default)
			)
			(layer "F.SilkS")
		)
		(fp_line
			(start 0.90678 0.4826)
			(end -0.90678 0.4826)
			(stroke
				(width 0.1524)
				(type default)
			)
			(layer "F.SilkS")
		)
		(fp_line
			(start -0.90678 0.4826)
			(end -0.90678 -0.4699)
			(stroke
				(width 0.1524)
				(type default)
			)
			(layer "F.SilkS")
		)
		(fp_line
			(start 0.499872 -0.249936)
			(end 0.499872 0.249936)
			(stroke
				(width 0.1)
				(type default)
			)
			(layer "F.Fab")
		)
		(fp_line
			(start -0.499872 -0.249936)
			(end 0.499872 -0.249936)
			(stroke
				(width 0.1)
				(type default)
			)
			(layer "F.Fab")
		)
		(fp_line
			(start 0.499872 0.249936)
			(end -0.499872 0.249936)
			(stroke
				(width 0.1)
				(type default)
			)
			(layer "F.Fab")
		)
		(fp_line
			(start -0.499872 0.249936)
			(end -0.499872 -0.249936)
			(stroke
				(width 0.1)
				(type default)
			)
			(layer "F.Fab")
		)
		(pad "A" smd rect
			(at -0.47498 0 90)
			(size 0.6096 0.7112)
			(layers "F.Cu" "F.Mask" "F.Paste")
			(net "LED_PWRGD_PVDDIO_P0_R")
		)
		(pad "C" smd rect
			(at 0.47498 0 90)
			(size 0.6096 0.7112)
			(layers "F.Cu" "F.Mask" "F.Paste")
			(net "LED_PWRGD_PVDDIO_P0_D")
		)
	)
)
